FILE_TYPE = MACRO_DRAWING;
SET COLOR_WIRE YELLOW;
SET COLOR_PROP ORANGE;
SET COLOR_DOT WHITE;
SET COLOR_ARC YELLOW;
SET COLOR_BODY GREEN;
SET COLOR_NOTE PURPLE;
SET PROP_DISPLAY VALUE;
SET PAGE_NUMBER P33;
FORCEADD GENOA_SP5..40
R 1
(-4750 3750);
FORCEPROP 1 LAST LOCATION U25
R 1
J 0
(-8406 3355);
DISPLAY 0.489362 (-8406 3355);
PAINT SKYBLUE (-8406 3355);
FORCEPROP 0 LAST $SEC 40
R 1
J 0
(-1400 4325);
DISPLAY 0.680851 (-1400 4325);
PAINT MONO (-1400 4325);
DISPLAY INVISIBLE (-1400 4325);
FORCEPROP 0 LAST CDS_SEC 40
R 1
J 0
(-1100 4225);
DISPLAY 1.021277 (-1100 4225);
DISPLAY INVISIBLE (-1100 4225);
FORCEPROP 0 LASTPIN (-2650 4300) $PN AA42
R 1
J 0
(-2660 4310);
DISPLAY 0.489362 (-2660 4310);
PAINT MONO (-2660 4310);
FORCEPROP 0 LASTPIN (-2600 4300) $PN AA72
R 1
J 0
(-2610 4310);
DISPLAY 0.489362 (-2610 4310);
PAINT MONO (-2610 4310);
FORCEPROP 0 LASTPIN (-2550 4300) $PN AD31
R 1
J 0
(-2560 4310);
DISPLAY 0.489362 (-2560 4310);
PAINT MONO (-2560 4310);
FORCEPROP 0 LASTPIN (-2500 4300) $PN AE4
R 1
J 0
(-2510 4310);
DISPLAY 0.489362 (-2510 4310);
PAINT MONO (-2510 4310);
FORCEPROP 0 LASTPIN (-2450 4300) $PN AH33
R 1
J 0
(-2460 4310);
DISPLAY 0.489362 (-2460 4310);
PAINT MONO (-2460 4310);
FORCEPROP 0 LASTPIN (-2400 4300) $PN AJ13
R 1
J 0
(-2410 4310);
DISPLAY 0.489362 (-2410 4310);
PAINT MONO (-2410 4310);
FORCEPROP 0 LASTPIN (-2350 4300) $PN AM37
R 1
J 0
(-2360 4310);
DISPLAY 0.489362 (-2360 4310);
PAINT MONO (-2360 4310);
FORCEPROP 0 LASTPIN (-2300 4300) $PN AN20
R 1
J 0
(-2310 4310);
DISPLAY 0.489362 (-2310 4310);
PAINT MONO (-2310 4310);
FORCEPROP 0 LASTPIN (-2250 4300) $PN BV42
R 1
J 0
(-2260 4310);
DISPLAY 0.489362 (-2260 4310);
PAINT MONO (-2260 4310);
FORCEPROP 0 LASTPIN (-2200 4300) $PN BW25
R 1
J 0
(-2210 4310);
DISPLAY 0.489362 (-2210 4310);
PAINT MONO (-2210 4310);
FORCEPROP 0 LASTPIN (-2150 4300) $PN CB44
R 1
J 0
(-2160 4310);
DISPLAY 0.489362 (-2160 4310);
PAINT MONO (-2160 4310);
FORCEPROP 0 LASTPIN (-2100 4300) $PN CC22
R 1
J 0
(-2110 4310);
DISPLAY 0.489362 (-2110 4310);
PAINT MONO (-2110 4310);
FORCEPROP 0 LASTPIN (-2050 4300) $PN CF46
R 1
J 0
(-2060 4310);
DISPLAY 0.489362 (-2060 4310);
PAINT MONO (-2060 4310);
FORCEPROP 0 LASTPIN (-2000 4300) $PN CG42
R 1
J 0
(-2010 4310);
DISPLAY 0.489362 (-2010 4310);
PAINT MONO (-2010 4310);
FORCEPROP 0 LASTPIN (-1950 4300) $PN CK10
R 1
J 0
(-1960 4310);
DISPLAY 0.489362 (-1960 4310);
PAINT MONO (-1960 4310);
FORCEPROP 0 LASTPIN (-1900 4300) $PN CK31
R 1
J 0
(-1910 4310);
DISPLAY 0.489362 (-1910 4310);
PAINT MONO (-1910 4310);
FORCEPROP 0 LASTPIN (-1850 4300) $PN CM50
R 1
J 0
(-1860 4310);
DISPLAY 0.489362 (-1860 4310);
PAINT MONO (-1860 4310);
FORCEPROP 0 LASTPIN (-1800 4300) $PN CN54
R 1
J 0
(-1810 4310);
DISPLAY 0.489362 (-1810 4310);
PAINT MONO (-1810 4310);
FORCEPROP 0 LASTPIN (-1750 4300) $PN CT52
R 1
J 0
(-1760 4310);
DISPLAY 0.489362 (-1760 4310);
PAINT MONO (-1760 4310);
FORCEPROP 0 LASTPIN (-1700 4300) $PN CU58
R 1
J 0
(-1710 4310);
DISPLAY 0.489362 (-1710 4310);
PAINT MONO (-1710 4310);
FORCEPROP 0 LASTPIN (-1650 4300) $PN CY57
R 1
J 0
(-1660 4310);
DISPLAY 0.489362 (-1660 4310);
PAINT MONO (-1660 4310);
FORCEPROP 0 LASTPIN (-1600 4300) $PN DA56
R 1
J 0
(-1610 4310);
DISPLAY 0.489362 (-1610 4310);
PAINT MONO (-1610 4310);
FORCEPROP 0 LASTPIN (-8000 3200) $PN DA72
R 1
J 2
(-8010 3190);
DISPLAY 0.489362 (-8010 3190);
PAINT MONO (-8010 3190);
FORCEPROP 0 LASTPIN (-7950 3200) $PN DA75
R 1
J 2
(-7960 3190);
DISPLAY 0.489362 (-7960 3190);
PAINT MONO (-7960 3190);
FORCEPROP 0 LASTPIN (-7900 3200) $PN DB3
R 1
J 2
(-7910 3190);
DISPLAY 0.489362 (-7910 3190);
PAINT MONO (-7910 3190);
FORCEPROP 0 LASTPIN (-7850 3200) $PN DB8
R 1
J 2
(-7860 3190);
DISPLAY 0.489362 (-7860 3190);
PAINT MONO (-7860 3190);
FORCEPROP 0 LASTPIN (-7800 3200) $PN DB10
R 1
J 2
(-7810 3190);
DISPLAY 0.489362 (-7810 3190);
PAINT MONO (-7810 3190);
FORCEPROP 0 LASTPIN (-7750 3200) $PN DB15
R 1
J 2
(-7760 3190);
DISPLAY 0.489362 (-7760 3190);
PAINT MONO (-7760 3190);
FORCEPROP 0 LASTPIN (-7700 3200) $PN DB17
R 1
J 2
(-7710 3190);
DISPLAY 0.489362 (-7710 3190);
PAINT MONO (-7710 3190);
FORCEPROP 0 LASTPIN (-7650 3200) $PN DB22
R 1
J 2
(-7660 3190);
DISPLAY 0.489362 (-7660 3190);
PAINT MONO (-7660 3190);
FORCEPROP 0 LASTPIN (-7600 3200) $PN DB25
R 1
J 2
(-7610 3190);
DISPLAY 0.489362 (-7610 3190);
PAINT MONO (-7610 3190);
FORCEPROP 0 LASTPIN (-7550 3200) $PN DB28
R 1
J 2
(-7560 3190);
DISPLAY 0.489362 (-7560 3190);
PAINT MONO (-7560 3190);
FORCEPROP 0 LASTPIN (-7500 3200) $PN DB31
R 1
J 2
(-7510 3190);
DISPLAY 0.489362 (-7510 3190);
PAINT MONO (-7510 3190);
FORCEPROP 0 LASTPIN (-7450 3200) $PN DB34
R 1
J 2
(-7460 3190);
DISPLAY 0.489362 (-7460 3190);
PAINT MONO (-7460 3190);
FORCEPROP 0 LASTPIN (-7400 3200) $PN DB37
R 1
J 2
(-7410 3190);
DISPLAY 0.489362 (-7410 3190);
PAINT MONO (-7410 3190);
FORCEPROP 0 LASTPIN (-7350 3200) $PN DB39
R 1
J 2
(-7360 3190);
DISPLAY 0.489362 (-7360 3190);
PAINT MONO (-7360 3190);
FORCEPROP 0 LASTPIN (-7300 3200) $PN DB42
R 1
J 2
(-7310 3190);
DISPLAY 0.489362 (-7310 3190);
PAINT MONO (-7310 3190);
FORCEPROP 0 LASTPIN (-7250 3200) $PN DB45
R 1
J 2
(-7260 3190);
DISPLAY 0.489362 (-7260 3190);
PAINT MONO (-7260 3190);
FORCEPROP 0 LASTPIN (-7200 3200) $PN DB48
R 1
J 2
(-7210 3190);
DISPLAY 0.489362 (-7210 3190);
PAINT MONO (-7210 3190);
FORCEPROP 0 LASTPIN (-7150 3200) $PN DB51
R 1
J 2
(-7160 3190);
DISPLAY 0.489362 (-7160 3190);
PAINT MONO (-7160 3190);
FORCEPROP 0 LASTPIN (-7100 3200) $PN DB54
R 1
J 2
(-7110 3190);
DISPLAY 0.489362 (-7110 3190);
PAINT MONO (-7110 3190);
FORCEPROP 0 LASTPIN (-7050 3200) $PN DB59
R 1
J 2
(-7060 3190);
DISPLAY 0.489362 (-7060 3190);
PAINT MONO (-7060 3190);
FORCEPROP 0 LASTPIN (-7000 3200) $PN DB61
R 1
J 2
(-7010 3190);
DISPLAY 0.489362 (-7010 3190);
PAINT MONO (-7010 3190);
FORCEPROP 0 LASTPIN (-6950 3200) $PN DB66
R 1
J 2
(-6960 3190);
DISPLAY 0.489362 (-6960 3190);
PAINT MONO (-6960 3190);
FORCEPROP 0 LASTPIN (-6900 3200) $PN DB68
R 1
J 2
(-6910 3190);
DISPLAY 0.489362 (-6910 3190);
PAINT MONO (-6910 3190);
FORCEPROP 0 LASTPIN (-6850 3200) $PN DB73
R 1
J 2
(-6860 3190);
DISPLAY 0.489362 (-6860 3190);
PAINT MONO (-6860 3190);
FORCEPROP 0 LASTPIN (-6800 3200) $PN DC1
R 1
J 2
(-6810 3190);
DISPLAY 0.489362 (-6810 3190);
PAINT MONO (-6810 3190);
FORCEPROP 0 LASTPIN (-6750 3200) $PN DC4
R 1
J 2
(-6760 3190);
DISPLAY 0.489362 (-6760 3190);
PAINT MONO (-6760 3190);
FORCEPROP 0 LASTPIN (-6700 3200) $PN DC6
R 1
J 2
(-6710 3190);
DISPLAY 0.489362 (-6710 3190);
PAINT MONO (-6710 3190);
FORCEPROP 0 LASTPIN (-6650 3200) $PN DC8
R 1
J 2
(-6660 3190);
DISPLAY 0.489362 (-6660 3190);
PAINT MONO (-6660 3190);
FORCEPROP 0 LASTPIN (-6600 3200) $PN DC11
R 1
J 2
(-6610 3190);
DISPLAY 0.489362 (-6610 3190);
PAINT MONO (-6610 3190);
FORCEPROP 0 LASTPIN (-6550 3200) $PN DC13
R 1
J 2
(-6560 3190);
DISPLAY 0.489362 (-6560 3190);
PAINT MONO (-6560 3190);
FORCEPROP 0 LASTPIN (-6500 3200) $PN DC15
R 1
J 2
(-6510 3190);
DISPLAY 0.489362 (-6510 3190);
PAINT MONO (-6510 3190);
FORCEPROP 0 LASTPIN (-6450 3200) $PN DC18
R 1
J 2
(-6460 3190);
DISPLAY 0.489362 (-6460 3190);
PAINT MONO (-6460 3190);
FORCEPROP 0 LASTPIN (-6400 3200) $PN DC20
R 1
J 2
(-6410 3190);
DISPLAY 0.489362 (-6410 3190);
PAINT MONO (-6410 3190);
FORCEPROP 0 LASTPIN (-6350 3200) $PN DC22
R 1
J 2
(-6360 3190);
DISPLAY 0.489362 (-6360 3190);
PAINT MONO (-6360 3190);
FORCEPROP 0 LASTPIN (-6300 3200) $PN DC25
R 1
J 2
(-6310 3190);
DISPLAY 0.489362 (-6310 3190);
PAINT MONO (-6310 3190);
FORCEPROP 0 LASTPIN (-6250 3200) $PN DC28
R 1
J 2
(-6260 3190);
DISPLAY 0.489362 (-6260 3190);
PAINT MONO (-6260 3190);
FORCEPROP 0 LASTPIN (-6200 3200) $PN DC31
R 1
J 2
(-6210 3190);
DISPLAY 0.489362 (-6210 3190);
PAINT MONO (-6210 3190);
FORCEPROP 0 LASTPIN (-6150 3200) $PN DC34
R 1
J 2
(-6160 3190);
DISPLAY 0.489362 (-6160 3190);
PAINT MONO (-6160 3190);
FORCEPROP 0 LASTPIN (-6100 3200) $PN DC42
R 1
J 2
(-6110 3190);
DISPLAY 0.489362 (-6110 3190);
PAINT MONO (-6110 3190);
FORCEPROP 0 LASTPIN (-6050 3200) $PN DC45
R 1
J 2
(-6060 3190);
DISPLAY 0.489362 (-6060 3190);
PAINT MONO (-6060 3190);
FORCEPROP 0 LASTPIN (-6000 3200) $PN DC48
R 1
J 2
(-6010 3190);
DISPLAY 0.489362 (-6010 3190);
PAINT MONO (-6010 3190);
FORCEPROP 0 LASTPIN (-5950 3200) $PN DC51
R 1
J 2
(-5960 3190);
DISPLAY 0.489362 (-5960 3190);
PAINT MONO (-5960 3190);
FORCEPROP 0 LASTPIN (-5900 3200) $PN DC54
R 1
J 2
(-5910 3190);
DISPLAY 0.489362 (-5910 3190);
PAINT MONO (-5910 3190);
FORCEPROP 0 LASTPIN (-5850 3200) $PN DC56
R 1
J 2
(-5860 3190);
DISPLAY 0.489362 (-5860 3190);
PAINT MONO (-5860 3190);
FORCEPROP 0 LASTPIN (-5800 3200) $PN DC58
R 1
J 2
(-5810 3190);
DISPLAY 0.489362 (-5810 3190);
PAINT MONO (-5810 3190);
FORCEPROP 0 LASTPIN (-5750 3200) $PN DC61
R 1
J 2
(-5760 3190);
DISPLAY 0.489362 (-5760 3190);
PAINT MONO (-5760 3190);
FORCEPROP 0 LASTPIN (-5700 3200) $PN DC63
R 1
J 2
(-5710 3190);
DISPLAY 0.489362 (-5710 3190);
PAINT MONO (-5710 3190);
FORCEPROP 0 LASTPIN (-5650 3200) $PN DC65
R 1
J 2
(-5660 3190);
DISPLAY 0.489362 (-5660 3190);
PAINT MONO (-5660 3190);
FORCEPROP 0 LASTPIN (-5600 3200) $PN DC68
R 1
J 2
(-5610 3190);
DISPLAY 0.489362 (-5610 3190);
PAINT MONO (-5610 3190);
FORCEPROP 0 LASTPIN (-5550 3200) $PN DC70
R 1
J 2
(-5560 3190);
DISPLAY 0.489362 (-5560 3190);
PAINT MONO (-5560 3190);
FORCEPROP 0 LASTPIN (-5500 3200) $PN DC72
R 1
J 2
(-5510 3190);
DISPLAY 0.489362 (-5510 3190);
PAINT MONO (-5510 3190);
FORCEPROP 0 LASTPIN (-5450 3200) $PN DC75
R 1
J 2
(-5460 3190);
DISPLAY 0.489362 (-5460 3190);
PAINT MONO (-5460 3190);
FORCEPROP 0 LASTPIN (-5400 3200) $PN DD3
R 1
J 2
(-5410 3190);
DISPLAY 0.489362 (-5410 3190);
PAINT MONO (-5410 3190);
FORCEPROP 0 LASTPIN (-5350 3200) $PN DD5
R 1
J 2
(-5360 3190);
DISPLAY 0.489362 (-5360 3190);
PAINT MONO (-5360 3190);
FORCEPROP 0 LASTPIN (-5300 3200) $PN DD8
R 1
J 2
(-5310 3190);
DISPLAY 0.489362 (-5310 3190);
PAINT MONO (-5310 3190);
FORCEPROP 0 LASTPIN (-5250 3200) $PN DD10
R 1
J 2
(-5260 3190);
DISPLAY 0.489362 (-5260 3190);
PAINT MONO (-5260 3190);
FORCEPROP 0 LASTPIN (-5200 3200) $PN DD12
R 1
J 2
(-5210 3190);
DISPLAY 0.489362 (-5210 3190);
PAINT MONO (-5210 3190);
FORCEPROP 0 LASTPIN (-5150 3200) $PN DD15
R 1
J 2
(-5160 3190);
DISPLAY 0.489362 (-5160 3190);
PAINT MONO (-5160 3190);
FORCEPROP 0 LASTPIN (-5100 3200) $PN DD17
R 1
J 2
(-5110 3190);
DISPLAY 0.489362 (-5110 3190);
PAINT MONO (-5110 3190);
FORCEPROP 0 LASTPIN (-5050 3200) $PN DD19
R 1
J 2
(-5060 3190);
DISPLAY 0.489362 (-5060 3190);
PAINT MONO (-5060 3190);
FORCEPROP 0 LASTPIN (-5000 3200) $PN DD23
R 1
J 2
(-5010 3190);
DISPLAY 0.489362 (-5010 3190);
PAINT MONO (-5010 3190);
FORCEPROP 0 LASTPIN (-4950 3200) $PN DD24
R 1
J 2
(-4960 3190);
DISPLAY 0.489362 (-4960 3190);
PAINT MONO (-4960 3190);
FORCEPROP 0 LASTPIN (-4900 3200) $PN DD26
R 1
J 2
(-4910 3190);
DISPLAY 0.489362 (-4910 3190);
PAINT MONO (-4910 3190);
FORCEPROP 0 LASTPIN (-4850 3200) $PN DD27
R 1
J 2
(-4860 3190);
DISPLAY 0.489362 (-4860 3190);
PAINT MONO (-4860 3190);
FORCEPROP 0 LASTPIN (-4800 3200) $PN DD29
R 1
J 2
(-4810 3190);
DISPLAY 0.489362 (-4810 3190);
PAINT MONO (-4810 3190);
FORCEPROP 0 LASTPIN (-4750 3200) $PN DD30
R 1
J 2
(-4760 3190);
DISPLAY 0.489362 (-4760 3190);
PAINT MONO (-4760 3190);
FORCEPROP 0 LASTPIN (-4700 3200) $PN DD32
R 1
J 2
(-4710 3190);
DISPLAY 0.489362 (-4710 3190);
PAINT MONO (-4710 3190);
FORCEPROP 0 LASTPIN (-4650 3200) $PN DD33
R 1
J 2
(-4660 3190);
DISPLAY 0.489362 (-4660 3190);
PAINT MONO (-4660 3190);
FORCEPROP 0 LASTPIN (-4600 3200) $PN DD35
R 1
J 2
(-4610 3190);
DISPLAY 0.489362 (-4610 3190);
PAINT MONO (-4610 3190);
FORCEPROP 0 LASTPIN (-4550 3200) $PN DD36
R 1
J 2
(-4560 3190);
DISPLAY 0.489362 (-4560 3190);
PAINT MONO (-4560 3190);
FORCEPROP 0 LASTPIN (-4500 3200) $PN DD37
R 1
J 2
(-4510 3190);
DISPLAY 0.489362 (-4510 3190);
PAINT MONO (-4510 3190);
FORCEPROP 0 LASTPIN (-4450 3200) $PN DD39
R 1
J 2
(-4460 3190);
DISPLAY 0.489362 (-4460 3190);
PAINT MONO (-4460 3190);
FORCEPROP 0 LASTPIN (-4400 3200) $PN DD40
R 1
J 2
(-4410 3190);
DISPLAY 0.489362 (-4410 3190);
PAINT MONO (-4410 3190);
FORCEPROP 0 LASTPIN (-4350 3200) $PN DD41
R 1
J 2
(-4360 3190);
DISPLAY 0.489362 (-4360 3190);
PAINT MONO (-4360 3190);
FORCEPROP 0 LASTPIN (-4300 3200) $PN DD43
R 1
J 2
(-4310 3190);
DISPLAY 0.489362 (-4310 3190);
PAINT MONO (-4310 3190);
FORCEPROP 0 LASTPIN (-4250 3200) $PN DD44
R 1
J 2
(-4260 3190);
DISPLAY 0.489362 (-4260 3190);
PAINT MONO (-4260 3190);
FORCEPROP 0 LASTPIN (-4200 3200) $PN DD46
R 1
J 2
(-4210 3190);
DISPLAY 0.489362 (-4210 3190);
PAINT MONO (-4210 3190);
FORCEPROP 0 LASTPIN (-4150 3200) $PN DD47
R 1
J 2
(-4160 3190);
DISPLAY 0.489362 (-4160 3190);
PAINT MONO (-4160 3190);
FORCEPROP 0 LASTPIN (-4100 3200) $PN DD49
R 1
J 2
(-4110 3190);
DISPLAY 0.489362 (-4110 3190);
PAINT MONO (-4110 3190);
FORCEPROP 0 LASTPIN (-4050 3200) $PN DD50
R 1
J 2
(-4060 3190);
DISPLAY 0.489362 (-4060 3190);
PAINT MONO (-4060 3190);
FORCEPROP 0 LASTPIN (-4000 3200) $PN DD52
R 1
J 2
(-4010 3190);
DISPLAY 0.489362 (-4010 3190);
PAINT MONO (-4010 3190);
FORCEPROP 0 LASTPIN (-3950 3200) $PN DD53
R 1
J 2
(-3960 3190);
DISPLAY 0.489362 (-3960 3190);
PAINT MONO (-3960 3190);
FORCEPROP 0 LASTPIN (-3900 3200) $PN DD57
R 1
J 2
(-3910 3190);
DISPLAY 0.489362 (-3910 3190);
PAINT MONO (-3910 3190);
FORCEPROP 0 LASTPIN (-3850 3200) $PN DD59
R 1
J 2
(-3860 3190);
DISPLAY 0.489362 (-3860 3190);
PAINT MONO (-3860 3190);
FORCEPROP 0 LASTPIN (-3800 3200) $PN DD61
R 1
J 2
(-3810 3190);
DISPLAY 0.489362 (-3810 3190);
PAINT MONO (-3810 3190);
FORCEPROP 0 LASTPIN (-3750 3200) $PN DD64
R 1
J 2
(-3760 3190);
DISPLAY 0.489362 (-3760 3190);
PAINT MONO (-3760 3190);
FORCEPROP 0 LASTPIN (-3700 3200) $PN DD66
R 1
J 2
(-3710 3190);
DISPLAY 0.489362 (-3710 3190);
PAINT MONO (-3710 3190);
FORCEPROP 0 LASTPIN (-3650 3200) $PN DD68
R 1
J 2
(-3660 3190);
DISPLAY 0.489362 (-3660 3190);
PAINT MONO (-3660 3190);
FORCEPROP 0 LASTPIN (-3600 3200) $PN DD71
R 1
J 2
(-3610 3190);
DISPLAY 0.489362 (-3610 3190);
PAINT MONO (-3610 3190);
FORCEPROP 0 LASTPIN (-3550 3200) $PN DD73
R 1
J 2
(-3560 3190);
DISPLAY 0.489362 (-3560 3190);
PAINT MONO (-3560 3190);
FORCEPROP 0 LASTPIN (-3500 3200) $PN DE1
R 1
J 2
(-3510 3190);
DISPLAY 0.489362 (-3510 3190);
PAINT MONO (-3510 3190);
FORCEPROP 0 LASTPIN (-3450 3200) $PN DE6
R 1
J 2
(-3460 3190);
DISPLAY 0.489362 (-3460 3190);
PAINT MONO (-3460 3190);
FORCEPROP 0 LASTPIN (-3400 3200) $PN DE8
R 1
J 2
(-3410 3190);
DISPLAY 0.489362 (-3410 3190);
PAINT MONO (-3410 3190);
FORCEPROP 0 LASTPIN (-3350 3200) $PN DE13
R 1
J 2
(-3360 3190);
DISPLAY 0.489362 (-3360 3190);
PAINT MONO (-3360 3190);
FORCEPROP 0 LASTPIN (-3300 3200) $PN DE15
R 1
J 2
(-3310 3190);
DISPLAY 0.489362 (-3310 3190);
PAINT MONO (-3310 3190);
FORCEPROP 0 LASTPIN (-3250 3200) $PN DE20
R 1
J 2
(-3260 3190);
DISPLAY 0.489362 (-3260 3190);
PAINT MONO (-3260 3190);
FORCEPROP 0 LASTPIN (-3200 3200) $PN DE23
R 1
J 2
(-3210 3190);
DISPLAY 0.489362 (-3210 3190);
PAINT MONO (-3210 3190);
FORCEPROP 0 LASTPIN (-3150 3200) $PN DE26
R 1
J 2
(-3160 3190);
DISPLAY 0.489362 (-3160 3190);
PAINT MONO (-3160 3190);
FORCEPROP 0 LASTPIN (-3100 3200) $PN DE29
R 1
J 2
(-3110 3190);
DISPLAY 0.489362 (-3110 3190);
PAINT MONO (-3110 3190);
FORCEPROP 0 LASTPIN (-3050 3200) $PN DE33
R 1
J 2
(-3060 3190);
DISPLAY 0.489362 (-3060 3190);
PAINT MONO (-3060 3190);
FORCEPROP 0 LASTPIN (-3000 3200) $PN DE56
R 1
J 2
(-3010 3190);
DISPLAY 0.489362 (-3010 3190);
PAINT MONO (-3010 3190);
FORCEPROP 0 LASTPIN (-2950 3200) $PN DE61
R 1
J 2
(-2960 3190);
DISPLAY 0.489362 (-2960 3190);
PAINT MONO (-2960 3190);
FORCEPROP 0 LASTPIN (-2900 3200) $PN DE63
R 1
J 2
(-2910 3190);
DISPLAY 0.489362 (-2910 3190);
PAINT MONO (-2910 3190);
FORCEPROP 0 LASTPIN (-2850 3200) $PN DE68
R 1
J 2
(-2860 3190);
DISPLAY 0.489362 (-2860 3190);
PAINT MONO (-2860 3190);
FORCEPROP 0 LASTPIN (-2800 3200) $PN DE70
R 1
J 2
(-2810 3190);
DISPLAY 0.489362 (-2810 3190);
PAINT MONO (-2810 3190);
FORCEPROP 0 LASTPIN (-2750 3200) $PN DE75
R 1
J 2
(-2760 3190);
DISPLAY 0.489362 (-2760 3190);
PAINT MONO (-2760 3190);
FORCEPROP 0 LASTPIN (-2700 3200) $PN DF3
R 1
J 2
(-2710 3190);
DISPLAY 0.489362 (-2710 3190);
PAINT MONO (-2710 3190);
FORCEPROP 0 LASTPIN (-2650 3200) $PN DF4
R 1
J 2
(-2660 3190);
DISPLAY 0.489362 (-2660 3190);
PAINT MONO (-2660 3190);
FORCEPROP 0 LASTPIN (-2600 3200) $PN DF5
R 1
J 2
(-2610 3190);
DISPLAY 0.489362 (-2610 3190);
PAINT MONO (-2610 3190);
FORCEPROP 0 LASTPIN (-2550 3200) $PN DF6
R 1
J 2
(-2560 3190);
DISPLAY 0.489362 (-2560 3190);
PAINT MONO (-2560 3190);
FORCEPROP 0 LASTPIN (-2500 3200) $PN DF8
R 1
J 2
(-2510 3190);
DISPLAY 0.489362 (-2510 3190);
PAINT MONO (-2510 3190);
FORCEPROP 0 LASTPIN (-2450 3200) $PN DF10
R 1
J 2
(-2460 3190);
DISPLAY 0.489362 (-2460 3190);
PAINT MONO (-2460 3190);
FORCEPROP 0 LASTPIN (-2400 3200) $PN DF11
R 1
J 2
(-2410 3190);
DISPLAY 0.489362 (-2410 3190);
PAINT MONO (-2410 3190);
FORCEPROP 0 LASTPIN (-2350 3200) $PN DF12
R 1
J 2
(-2360 3190);
DISPLAY 0.489362 (-2360 3190);
PAINT MONO (-2360 3190);
FORCEPROP 0 LASTPIN (-2300 3200) $PN DF13
R 1
J 2
(-2310 3190);
DISPLAY 0.489362 (-2310 3190);
PAINT MONO (-2310 3190);
FORCEPROP 0 LASTPIN (-2250 3200) $PN DF15
R 1
J 2
(-2260 3190);
DISPLAY 0.489362 (-2260 3190);
PAINT MONO (-2260 3190);
FORCEPROP 0 LASTPIN (-2200 3200) $PN DF17
R 1
J 2
(-2210 3190);
DISPLAY 0.489362 (-2210 3190);
PAINT MONO (-2210 3190);
FORCEPROP 0 LASTPIN (-2150 3200) $PN DF18
R 1
J 2
(-2160 3190);
DISPLAY 0.489362 (-2160 3190);
PAINT MONO (-2160 3190);
FORCEPROP 0 LASTPIN (-2100 3200) $PN DF19
R 1
J 2
(-2110 3190);
DISPLAY 0.489362 (-2110 3190);
PAINT MONO (-2110 3190);
FORCEPROP 0 LASTPIN (-8000 4300) $PN DF20
R 1
J 0
(-8010 4310);
DISPLAY 0.489362 (-8010 4310);
PAINT MONO (-8010 4310);
FORCEPROP 0 LASTPIN (-7950 4300) $PN DF22
R 1
J 0
(-7960 4310);
DISPLAY 0.489362 (-7960 4310);
PAINT MONO (-7960 4310);
FORCEPROP 0 LASTPIN (-7900 4300) $PN DF23
R 1
J 0
(-7910 4310);
DISPLAY 0.489362 (-7910 4310);
PAINT MONO (-7910 4310);
FORCEPROP 0 LASTPIN (-7850 4300) $PN DF26
R 1
J 0
(-7860 4310);
DISPLAY 0.489362 (-7860 4310);
PAINT MONO (-7860 4310);
FORCEPROP 0 LASTPIN (-7800 4300) $PN DF29
R 1
J 0
(-7810 4310);
DISPLAY 0.489362 (-7810 4310);
PAINT MONO (-7810 4310);
FORCEPROP 0 LASTPIN (-7750 4300) $PN DF32
R 1
J 0
(-7760 4310);
DISPLAY 0.489362 (-7760 4310);
PAINT MONO (-7760 4310);
FORCEPROP 0 LASTPIN (-7700 4300) $PN DF35
R 1
J 0
(-7710 4310);
DISPLAY 0.489362 (-7710 4310);
PAINT MONO (-7710 4310);
FORCEPROP 0 LASTPIN (-7650 4300) $PN DF37
R 1
J 0
(-7660 4310);
DISPLAY 0.489362 (-7660 4310);
PAINT MONO (-7660 4310);
FORCEPROP 0 LASTPIN (-7600 4300) $PN DF39
R 1
J 0
(-7610 4310);
DISPLAY 0.489362 (-7610 4310);
PAINT MONO (-7610 4310);
FORCEPROP 0 LASTPIN (-7550 4300) $PN DF42
R 1
J 0
(-7560 4310);
DISPLAY 0.489362 (-7560 4310);
PAINT MONO (-7560 4310);
FORCEPROP 0 LASTPIN (-7500 4300) $PN DF43
R 1
J 0
(-7510 4310);
DISPLAY 0.489362 (-7510 4310);
PAINT MONO (-7510 4310);
FORCEPROP 0 LASTPIN (-7450 4300) $PN DF44
R 1
J 0
(-7460 4310);
DISPLAY 0.489362 (-7460 4310);
PAINT MONO (-7460 4310);
FORCEPROP 0 LASTPIN (-7400 4300) $PN DF45
R 1
J 0
(-7410 4310);
DISPLAY 0.489362 (-7410 4310);
PAINT MONO (-7410 4310);
FORCEPROP 0 LASTPIN (-7350 4300) $PN DF46
R 1
J 0
(-7360 4310);
DISPLAY 0.489362 (-7360 4310);
PAINT MONO (-7360 4310);
FORCEPROP 0 LASTPIN (-7300 4300) $PN DF47
R 1
J 0
(-7310 4310);
DISPLAY 0.489362 (-7310 4310);
PAINT MONO (-7310 4310);
FORCEPROP 0 LASTPIN (-7250 4300) $PN DF48
R 1
J 0
(-7260 4310);
DISPLAY 0.489362 (-7260 4310);
PAINT MONO (-7260 4310);
FORCEPROP 0 LASTPIN (-7200 4300) $PN DF49
R 1
J 0
(-7210 4310);
DISPLAY 0.489362 (-7210 4310);
PAINT MONO (-7210 4310);
FORCEPROP 0 LASTPIN (-7150 4300) $PN DF50
R 1
J 0
(-7160 4310);
DISPLAY 0.489362 (-7160 4310);
PAINT MONO (-7160 4310);
FORCEPROP 0 LASTPIN (-7100 4300) $PN DF51
R 1
J 0
(-7110 4310);
DISPLAY 0.489362 (-7110 4310);
PAINT MONO (-7110 4310);
FORCEPROP 0 LASTPIN (-7050 4300) $PN DF52
R 1
J 0
(-7060 4310);
DISPLAY 0.489362 (-7060 4310);
PAINT MONO (-7060 4310);
FORCEPROP 0 LASTPIN (-7000 4300) $PN DF53
R 1
J 0
(-7010 4310);
DISPLAY 0.489362 (-7010 4310);
PAINT MONO (-7010 4310);
FORCEPROP 0 LASTPIN (-6950 4300) $PN DF54
R 1
J 0
(-6960 4310);
DISPLAY 0.489362 (-6960 4310);
PAINT MONO (-6960 4310);
FORCEPROP 0 LASTPIN (-6900 4300) $PN DF56
R 1
J 0
(-6910 4310);
DISPLAY 0.489362 (-6910 4310);
PAINT MONO (-6910 4310);
FORCEPROP 0 LASTPIN (-6850 4300) $PN DF57
R 1
J 0
(-6860 4310);
DISPLAY 0.489362 (-6860 4310);
PAINT MONO (-6860 4310);
FORCEPROP 0 LASTPIN (-6800 4300) $PN DF58
R 1
J 0
(-6810 4310);
DISPLAY 0.489362 (-6810 4310);
PAINT MONO (-6810 4310);
FORCEPROP 0 LASTPIN (-6750 4300) $PN DF59
R 1
J 0
(-6760 4310);
DISPLAY 0.489362 (-6760 4310);
PAINT MONO (-6760 4310);
FORCEPROP 0 LASTPIN (-6700 4300) $PN DF61
R 1
J 0
(-6710 4310);
DISPLAY 0.489362 (-6710 4310);
PAINT MONO (-6710 4310);
FORCEPROP 0 LASTPIN (-6650 4300) $PN DF63
R 1
J 0
(-6660 4310);
DISPLAY 0.489362 (-6660 4310);
PAINT MONO (-6660 4310);
FORCEPROP 0 LASTPIN (-6600 4300) $PN DF64
R 1
J 0
(-6610 4310);
DISPLAY 0.489362 (-6610 4310);
PAINT MONO (-6610 4310);
FORCEPROP 0 LASTPIN (-6550 4300) $PN DF65
R 1
J 0
(-6560 4310);
DISPLAY 0.489362 (-6560 4310);
PAINT MONO (-6560 4310);
FORCEPROP 0 LASTPIN (-6500 4300) $PN DF66
R 1
J 0
(-6510 4310);
DISPLAY 0.489362 (-6510 4310);
PAINT MONO (-6510 4310);
FORCEPROP 0 LASTPIN (-6450 4300) $PN DF68
R 1
J 0
(-6460 4310);
DISPLAY 0.489362 (-6460 4310);
PAINT MONO (-6460 4310);
FORCEPROP 0 LASTPIN (-6400 4300) $PN DF70
R 1
J 0
(-6410 4310);
DISPLAY 0.489362 (-6410 4310);
PAINT MONO (-6410 4310);
FORCEPROP 0 LASTPIN (-6350 4300) $PN DF71
R 1
J 0
(-6360 4310);
DISPLAY 0.489362 (-6360 4310);
PAINT MONO (-6360 4310);
FORCEPROP 0 LASTPIN (-6300 4300) $PN DF72
R 1
J 0
(-6310 4310);
DISPLAY 0.489362 (-6310 4310);
PAINT MONO (-6310 4310);
FORCEPROP 0 LASTPIN (-6250 4300) $PN DF73
R 1
J 0
(-6260 4310);
DISPLAY 0.489362 (-6260 4310);
PAINT MONO (-6260 4310);
FORCEPROP 0 LASTPIN (-6200 4300) $PN DG1
R 1
J 0
(-6210 4310);
DISPLAY 0.489362 (-6210 4310);
PAINT MONO (-6210 4310);
FORCEPROP 0 LASTPIN (-6150 4300) $PN DG2
R 1
J 0
(-6160 4310);
DISPLAY 0.489362 (-6160 4310);
PAINT MONO (-6160 4310);
FORCEPROP 0 LASTPIN (-6100 4300) $PN DG6
R 1
J 0
(-6110 4310);
DISPLAY 0.489362 (-6110 4310);
PAINT MONO (-6110 4310);
FORCEPROP 0 LASTPIN (-6050 4300) $PN DG7
R 1
J 0
(-6060 4310);
DISPLAY 0.489362 (-6060 4310);
PAINT MONO (-6060 4310);
FORCEPROP 0 LASTPIN (-6000 4300) $PN DG8
R 1
J 0
(-6010 4310);
DISPLAY 0.489362 (-6010 4310);
PAINT MONO (-6010 4310);
FORCEPROP 0 LASTPIN (-5950 4300) $PN DG9
R 1
J 0
(-5960 4310);
DISPLAY 0.489362 (-5960 4310);
PAINT MONO (-5960 4310);
FORCEPROP 0 LASTPIN (-5900 4300) $PN DG13
R 1
J 0
(-5910 4310);
DISPLAY 0.489362 (-5910 4310);
PAINT MONO (-5910 4310);
FORCEPROP 0 LASTPIN (-5850 4300) $PN DG14
R 1
J 0
(-5860 4310);
DISPLAY 0.489362 (-5860 4310);
PAINT MONO (-5860 4310);
FORCEPROP 0 LASTPIN (-5800 4300) $PN DG15
R 1
J 0
(-5810 4310);
DISPLAY 0.489362 (-5810 4310);
PAINT MONO (-5810 4310);
FORCEPROP 0 LASTPIN (-5750 4300) $PN DG16
R 1
J 0
(-5760 4310);
DISPLAY 0.489362 (-5760 4310);
PAINT MONO (-5760 4310);
FORCEPROP 0 LASTPIN (-5700 4300) $PN DG18
R 1
J 0
(-5710 4310);
DISPLAY 0.489362 (-5710 4310);
PAINT MONO (-5710 4310);
FORCEPROP 0 LASTPIN (-5650 4300) $PN DG20
R 1
J 0
(-5660 4310);
DISPLAY 0.489362 (-5660 4310);
PAINT MONO (-5660 4310);
FORCEPROP 0 LASTPIN (-5600 4300) $PN DG21
R 1
J 0
(-5610 4310);
DISPLAY 0.489362 (-5610 4310);
PAINT MONO (-5610 4310);
FORCEPROP 0 LASTPIN (-5550 4300) $PN DG24
R 1
J 0
(-5560 4310);
DISPLAY 0.489362 (-5560 4310);
PAINT MONO (-5560 4310);
FORCEPROP 0 LASTPIN (-5500 4300) $PN DG27
R 1
J 0
(-5510 4310);
DISPLAY 0.489362 (-5510 4310);
PAINT MONO (-5510 4310);
FORCEPROP 0 LASTPIN (-5450 4300) $PN DG30
R 1
J 0
(-5460 4310);
DISPLAY 0.489362 (-5460 4310);
PAINT MONO (-5460 4310);
FORCEPROP 0 LASTPIN (-5400 4300) $PN DG33
R 1
J 0
(-5410 4310);
DISPLAY 0.489362 (-5410 4310);
PAINT MONO (-5410 4310);
FORCEPROP 0 LASTPIN (-5350 4300) $PN DG41
R 1
J 0
(-5360 4310);
DISPLAY 0.489362 (-5360 4310);
PAINT MONO (-5360 4310);
FORCEPROP 0 LASTPIN (-5300 4300) $PN DG43
R 1
J 0
(-5310 4310);
DISPLAY 0.489362 (-5310 4310);
PAINT MONO (-5310 4310);
FORCEPROP 0 LASTPIN (-5250 4300) $PN DG46
R 1
J 0
(-5260 4310);
DISPLAY 0.489362 (-5260 4310);
PAINT MONO (-5260 4310);
FORCEPROP 0 LASTPIN (-5200 4300) $PN DG49
R 1
J 0
(-5210 4310);
DISPLAY 0.489362 (-5210 4310);
PAINT MONO (-5210 4310);
FORCEPROP 0 LASTPIN (-5150 4300) $PN DG52
R 1
J 0
(-5160 4310);
DISPLAY 0.489362 (-5160 4310);
PAINT MONO (-5160 4310);
FORCEPROP 0 LASTPIN (-5100 4300) $PN DG55
R 1
J 0
(-5110 4310);
DISPLAY 0.489362 (-5110 4310);
PAINT MONO (-5110 4310);
FORCEPROP 0 LASTPIN (-5050 4300) $PN DG56
R 1
J 0
(-5060 4310);
DISPLAY 0.489362 (-5060 4310);
PAINT MONO (-5060 4310);
FORCEPROP 0 LASTPIN (-5000 4300) $PN DG59
R 1
J 0
(-5010 4310);
DISPLAY 0.489362 (-5010 4310);
PAINT MONO (-5010 4310);
FORCEPROP 0 LASTPIN (-4950 4300) $PN DG60
R 1
J 0
(-4960 4310);
DISPLAY 0.489362 (-4960 4310);
PAINT MONO (-4960 4310);
FORCEPROP 0 LASTPIN (-4900 4300) $PN DG61
R 1
J 0
(-4910 4310);
DISPLAY 0.489362 (-4910 4310);
PAINT MONO (-4910 4310);
FORCEPROP 0 LASTPIN (-4850 4300) $PN DG62
R 1
J 0
(-4860 4310);
DISPLAY 0.489362 (-4860 4310);
PAINT MONO (-4860 4310);
FORCEPROP 0 LASTPIN (-4800 4300) $PN DG63
R 1
J 0
(-4810 4310);
DISPLAY 0.489362 (-4810 4310);
PAINT MONO (-4810 4310);
FORCEPROP 0 LASTPIN (-4750 4300) $PN DG65
R 1
J 0
(-4760 4310);
DISPLAY 0.489362 (-4760 4310);
PAINT MONO (-4760 4310);
FORCEPROP 0 LASTPIN (-4700 4300) $PN DG66
R 1
J 0
(-4710 4310);
DISPLAY 0.489362 (-4710 4310);
PAINT MONO (-4710 4310);
FORCEPROP 0 LASTPIN (-4650 4300) $PN DG67
R 1
J 0
(-4660 4310);
DISPLAY 0.489362 (-4660 4310);
PAINT MONO (-4660 4310);
FORCEPROP 0 LASTPIN (-4600 4300) $PN DG68
R 1
J 0
(-4610 4310);
DISPLAY 0.489362 (-4610 4310);
PAINT MONO (-4610 4310);
FORCEPROP 0 LASTPIN (-4550 4300) $PN DG69
R 1
J 0
(-4560 4310);
DISPLAY 0.489362 (-4560 4310);
PAINT MONO (-4560 4310);
FORCEPROP 0 LASTPIN (-4500 4300) $PN DG70
R 1
J 0
(-4510 4310);
DISPLAY 0.489362 (-4510 4310);
PAINT MONO (-4510 4310);
FORCEPROP 0 LASTPIN (-4450 4300) $PN DG74
R 1
J 0
(-4460 4310);
DISPLAY 0.489362 (-4460 4310);
PAINT MONO (-4460 4310);
FORCEPROP 0 LASTPIN (-4400 4300) $PN DG75
R 1
J 0
(-4410 4310);
DISPLAY 0.489362 (-4410 4310);
PAINT MONO (-4410 4310);
FORCEPROP 0 LASTPIN (-4350 4300) $PN DH5
R 1
J 0
(-4360 4310);
DISPLAY 0.489362 (-4360 4310);
PAINT MONO (-4360 4310);
FORCEPROP 0 LASTPIN (-4300 4300) $PN DH11
R 1
J 0
(-4310 4310);
DISPLAY 0.489362 (-4310 4310);
PAINT MONO (-4310 4310);
FORCEPROP 0 LASTPIN (-4250 4300) $PN DH18
R 1
J 0
(-4260 4310);
DISPLAY 0.489362 (-4260 4310);
PAINT MONO (-4260 4310);
FORCEPROP 0 LASTPIN (-4200 4300) $PN DH37
R 1
J 0
(-4210 4310);
DISPLAY 0.489362 (-4210 4310);
PAINT MONO (-4210 4310);
FORCEPROP 0 LASTPIN (-4150 4300) $PN DH39
R 1
J 0
(-4160 4310);
DISPLAY 0.489362 (-4160 4310);
PAINT MONO (-4160 4310);
FORCEPROP 0 LASTPIN (-4100 4300) $PN DH43
R 1
J 0
(-4110 4310);
DISPLAY 0.489362 (-4110 4310);
PAINT MONO (-4110 4310);
FORCEPROP 0 LASTPIN (-4050 4300) $PN DH46
R 1
J 0
(-4060 4310);
DISPLAY 0.489362 (-4060 4310);
PAINT MONO (-4060 4310);
FORCEPROP 0 LASTPIN (-4000 4300) $PN DH49
R 1
J 0
(-4010 4310);
DISPLAY 0.489362 (-4010 4310);
PAINT MONO (-4010 4310);
FORCEPROP 0 LASTPIN (-3950 4300) $PN DH52
R 1
J 0
(-3960 4310);
DISPLAY 0.489362 (-3960 4310);
PAINT MONO (-3960 4310);
FORCEPROP 0 LASTPIN (-3900 4300) $PN DH55
R 1
J 0
(-3910 4310);
DISPLAY 0.489362 (-3910 4310);
PAINT MONO (-3910 4310);
FORCEPROP 0 LASTPIN (-3850 4300) $PN DH59
R 1
J 0
(-3860 4310);
DISPLAY 0.489362 (-3860 4310);
PAINT MONO (-3860 4310);
FORCEPROP 0 LASTPIN (-3800 4300) $PN DH61
R 1
J 0
(-3810 4310);
DISPLAY 0.489362 (-3810 4310);
PAINT MONO (-3810 4310);
FORCEPROP 0 LASTPIN (-3750 4300) $PN DH63
R 1
J 0
(-3760 4310);
DISPLAY 0.489362 (-3760 4310);
PAINT MONO (-3760 4310);
FORCEPROP 0 LASTPIN (-3700 4300) $PN DH64
R 1
J 0
(-3710 4310);
DISPLAY 0.489362 (-3710 4310);
PAINT MONO (-3710 4310);
FORCEPROP 0 LASTPIN (-3650 4300) $PN DH66
R 1
J 0
(-3660 4310);
DISPLAY 0.489362 (-3660 4310);
PAINT MONO (-3660 4310);
FORCEPROP 0 LASTPIN (-3600 4300) $PN DH68
R 1
J 0
(-3610 4310);
DISPLAY 0.489362 (-3610 4310);
PAINT MONO (-3610 4310);
FORCEPROP 0 LASTPIN (-3550 4300) $PN DH70
R 1
J 0
(-3560 4310);
DISPLAY 0.489362 (-3560 4310);
PAINT MONO (-3560 4310);
FORCEPROP 0 LASTPIN (-3500 4300) $PN DJ7
R 1
J 0
(-3510 4310);
DISPLAY 0.489362 (-3510 4310);
PAINT MONO (-3510 4310);
FORCEPROP 0 LASTPIN (-3450 4300) $PN DJ15
R 1
J 0
(-3460 4310);
DISPLAY 0.489362 (-3460 4310);
PAINT MONO (-3460 4310);
FORCEPROP 0 LASTPIN (-3400 4300) $PN DJ19
R 1
J 0
(-3410 4310);
DISPLAY 0.489362 (-3410 4310);
PAINT MONO (-3410 4310);
FORCEPROP 0 LASTPIN (-3350 4300) $PN DJ43
R 1
J 0
(-3360 4310);
DISPLAY 0.489362 (-3360 4310);
PAINT MONO (-3360 4310);
FORCEPROP 0 LASTPIN (-3300 4300) $PN DJ49
R 1
J 0
(-3310 4310);
DISPLAY 0.489362 (-3310 4310);
PAINT MONO (-3310 4310);
FORCEPROP 0 LASTPIN (-3250 4300) $PN DJ59
R 1
J 0
(-3260 4310);
DISPLAY 0.489362 (-3260 4310);
PAINT MONO (-3260 4310);
FORCEPROP 0 LASTPIN (-3200 4300) $PN DJ61
R 1
J 0
(-3210 4310);
DISPLAY 0.489362 (-3210 4310);
PAINT MONO (-3210 4310);
FORCEPROP 0 LASTPIN (-3150 4300) $PN DJ63
R 1
J 0
(-3160 4310);
DISPLAY 0.489362 (-3160 4310);
PAINT MONO (-3160 4310);
FORCEPROP 0 LASTPIN (-3100 4300) $PN DJ66
R 1
J 0
(-3110 4310);
DISPLAY 0.489362 (-3110 4310);
PAINT MONO (-3110 4310);
FORCEPROP 0 LASTPIN (-3050 4300) $PN DJ68
R 1
J 0
(-3060 4310);
DISPLAY 0.489362 (-3060 4310);
PAINT MONO (-3060 4310);
FORCEPROP 0 LASTPIN (-3000 4300) $PN DJ73
R 1
J 0
(-3010 4310);
DISPLAY 0.489362 (-3010 4310);
PAINT MONO (-3010 4310);
FORCEPROP 0 LASTPIN (-2950 4300) $PN K23
R 1
J 0
(-2960 4310);
DISPLAY 0.489362 (-2960 4310);
PAINT MONO (-2960 4310);
FORCEPROP 0 LASTPIN (-2900 4300) $PN K59
R 1
J 0
(-2910 4310);
DISPLAY 0.489362 (-2910 4310);
PAINT MONO (-2910 4310);
FORCEPROP 0 LASTPIN (-2850 4300) $PN P25
R 1
J 0
(-2860 4310);
DISPLAY 0.489362 (-2860 4310);
PAINT MONO (-2860 4310);
FORCEPROP 0 LASTPIN (-2800 4300) $PN P68
R 1
J 0
(-2810 4310);
DISPLAY 0.489362 (-2810 4310);
PAINT MONO (-2810 4310);
FORCEPROP 0 LASTPIN (-2750 4300) $PN V27
R 1
J 0
(-2760 4310);
DISPLAY 0.489362 (-2760 4310);
PAINT MONO (-2760 4310);
FORCEPROP 0 LASTPIN (-2700 4300) $PN V68
R 1
J 0
(-2710 4310);
DISPLAY 0.489362 (-2710 4310);
PAINT MONO (-2710 4310);
FORCEPROP 2 LAST PART_TYPE SMLF
R 1
J 0
(-8575 3375);
DISPLAY 1.021277 (-8575 3375);
FORCEPROP 1 LAST MATERIAL IO
R 1
J 0
(-8132 3355);
DISPLAY 0.489362 (-8132 3355);
PAINT SKYBLUE (-8132 3355);
FORCEPROP 2 LAST VALUE SOCKET6096_13568-001
R 1
J 0
(-8200 3350);
DISPLAY 0.489362 (-8200 3350);
PAINT SKYBLUE (-8200 3350);
FORCEPROP 1 LAST PART_NUMBER DGA^6000030
R 1
J 0
(-8259 3355);
DISPLAY 0.489362 (-8259 3355);
PAINT SKYBLUE (-8259 3355);
FORCEPROP 1 LAST CDS_LMAN_SYM_OUTLINE -400,3350,400,-3350
R 1
J 0
(-4750 3750);
DISPLAY 0.468085 (-4750 3750);
PAINT GREEN (-4750 3750);
DISPLAY INVISIBLE (-4750 3750);
FORCEPROP 2 LAST CDS_LIB pure_quanta
J 0
(-4750 3750);
DISPLAY INVISIBLE (-4750 3750);
FORCEPROP 1 LAST NEEDS_NO_SIZE TRUE
R 1
J 0
(-4750 3750);
DISPLAY 0.723404 (-4750 3750);
PAINT GREEN (-4750 3750);
DISPLAY INVISIBLE (-4750 3750);
FORCEPROP 1 LAST PATH I4
R 1
J 0
(-4750 3750);
DISPLAY 0.723404 (-4750 3750);
PAINT GREEN (-4750 3750);
DISPLAY INVISIBLE (-4750 3750);
FORCEADD UNIVERSAL_GND..1
R 1
(-1300 4475);
FORCEPROP 3 LASTPIN (-1350 4475) SIG_NAME GND\g
J 0
(-1340 4485);
DISPLAY 0.659574 (-1340 4485);
PAINT MONO (-1340 4485);
DISPLAY INVISIBLE (-1340 4485);
FORCEPROP 2 LAST CDS_LIB pure_quanta_power
R 1
J 0
(-1300 4475);
DISPLAY INVISIBLE (-1300 4475);
FORCEPROP 1 LAST PATH I5
R 1
J 0
(-1300 4550);
DISPLAY 0.872340 (-1300 4550);
PAINT AQUA (-1300 4550);
DISPLAY INVISIBLE (-1300 4550);
FORCEPROP 1 LAST HDL_POWER GND
R 1
J 1
(-1225 4500);
DISPLAY 0.872340 (-1225 4500);
PAINT GREEN (-1225 4500);
DISPLAY INVISIBLE (-1225 4500);
FORCEADD UNIVERSAL_GND..1
R 1
(-1875 3025);
FORCEPROP 3 LASTPIN (-1925 3025) SIG_NAME GND\g
J 0
(-1915 3035);
DISPLAY 0.659574 (-1915 3035);
PAINT MONO (-1915 3035);
DISPLAY INVISIBLE (-1915 3035);
FORCEPROP 2 LAST CDS_LIB pure_quanta_power
R 1
J 0
(-1875 3025);
DISPLAY INVISIBLE (-1875 3025);
FORCEPROP 1 LAST PATH I6
R 1
J 0
(-1875 3100);
DISPLAY 0.872340 (-1875 3100);
PAINT AQUA (-1875 3100);
DISPLAY INVISIBLE (-1875 3100);
FORCEPROP 1 LAST HDL_POWER GND
R 1
J 1
(-1800 3050);
DISPLAY 0.872340 (-1800 3050);
PAINT GREEN (-1800 3050);
DISPLAY INVISIBLE (-1800 3050);
FORCEADD QUANTA_TITLE_BLOCK_C..1
(-100 100);
FORCEPROP 0 LAST CDS_CON_LAST_MODIFIED Fri Mar 11 14:52:28 2022
J 0
(-1985 115);
DISPLAY INVISIBLE (-1985 115);
FORCEPROP 1 LAST CUSTOM_TXT_CDS <CON_LAST_MODIFIED>
J 0
(-1985 115);
DISPLAY 0.978723 (-1985 115);
FORCEPROP 2 LAST CUSTOM_TXT_CDS <XR_PAGE_TITLE>
J 0
(-7990 5350);
DISPLAY 0.638298 (-7990 5350);
PAINT PINK (-7990 5350);
DISPLAY INVISIBLE (-7990 5350);
FORCEPROP 1 LAST CUSTOM_TXT_CDS <NAME_2>
J 0
(-3275 150);
FORCEPROP 1 LAST CUSTOM_TXT_CDS <NAME_1>
J 0
(-3275 275);
FORCEPROP 1 LAST CUSTOM_TXT_CDS <Q_NUMBER>
J 0
(-1503 203);
DISPLAY 1.212766 (-1503 203);
FORCEPROP 1 LAST CUSTOM_TXT_CDS <Q_PROJ>
J 0
(-2482 202);
DISPLAY 1.212766 (-2482 202);
FORCEPROP 1 LAST CUSTOM_TXT_CDS <Q_REV>
J 0
(-284 203);
DISPLAY 1.212766 (-284 203);
FORCEPROP 1 LAST CUSTOM_TXT_CDS <CON_PAGE_NUM> OF <CON_TOTAL_PAGES>
J 0
(-546 118);
DISPLAY 0.978723 (-546 118);
FORCEPROP 1 LAST Q_TITLE CPU0 VSS 3/3
J 0
(-9400 175);
DISPLAY 2.446809 (-9400 175);
PAINT GREEN (-9400 175);
FORCEPROP 1 LAST Q_DEPT BU9
J 1
(-3863 149);
DISPLAY 1.957447 (-3863 149);
PAINT GREEN (-3863 149);
FORCEPROP 2 LAST PAGE_BORDER TRUE
J 0
(-7990 5350);
DISPLAY 0.638298 (-7990 5350);
PAINT PINK (-7990 5350);
DISPLAY INVISIBLE (-7990 5350);
FORCEPROP 1 LAST CDS_LMAN_SYM_OUTLINE -9475,6775,100,-125
J 0
(-100 100);
DISPLAY 0.468085 (-100 100);
PAINT GREEN (-100 100);
DISPLAY INVISIBLE (-100 100);
FORCEPROP 2 LAST CDS_LIB pure_quanta
J 0
(-100 100);
DISPLAY INVISIBLE (-100 100);
FORCEPROP 1 LAST COMMENT_BODY TRUE
J 0
(-88 87);
DISPLAY 0.978723 (-88 87);
PAINT GREEN (-88 87);
DISPLAY INVISIBLE (-88 87);
FORCEPROP 2 LAST CDS_XR_PAGE_TITLE CR-33 : @T6G_MB_LIB.T6G(SCH_1):PAGE33
J 0
(-7990 5350);
DISPLAY 0.638298 (-7990 5350);
PAINT PINK (-7990 5350);
DISPLAY INVISIBLE (-7990 5350);
WIRE 16 -1 (-8000 3200)(-8000 3025);
WIRE 16 -1 (-8000 3025)(-7950 3025);
WIRE 16 -1 (-7950 3025)(-7950 3200);
WIRE 16 -1 (-7950 3025)(-7900 3025);
WIRE 16 -1 (-7900 3200)(-7900 3025);
WIRE 16 -1 (-7900 3025)(-7850 3025);
WIRE 16 -1 (-7850 3025)(-7850 3200);
WIRE 16 -1 (-7850 3025)(-7800 3025);
WIRE 16 -1 (-7800 3025)(-7800 3200);
WIRE 16 -1 (-7800 3025)(-7750 3025);
WIRE 16 -1 (-7750 3200)(-7750 3025);
WIRE 16 -1 (-7750 3025)(-7700 3025);
WIRE 16 -1 (-7700 3025)(-7700 3200);
WIRE 16 -1 (-7700 3025)(-7650 3025);
WIRE 16 -1 (-7650 3025)(-7650 3200);
WIRE 16 -1 (-7650 3025)(-7600 3025);
WIRE 16 -1 (-7600 3200)(-7600 3025);
WIRE 16 -1 (-7600 3025)(-7550 3025);
WIRE 16 -1 (-7550 3025)(-7550 3200);
WIRE 16 -1 (-7550 3025)(-7500 3025);
WIRE 16 -1 (-7500 3200)(-7500 3025);
WIRE 16 -1 (-7500 3025)(-7450 3025);
WIRE 16 -1 (-7450 3025)(-7450 3200);
WIRE 16 -1 (-7450 3025)(-7400 3025);
WIRE 16 -1 (-7400 3025)(-7400 3200);
WIRE 16 -1 (-7400 3025)(-7350 3025);
WIRE 16 -1 (-7350 3200)(-7350 3025);
WIRE 16 -1 (-7350 3025)(-7300 3025);
WIRE 16 -1 (-7300 3025)(-7300 3200);
WIRE 16 -1 (-7300 3025)(-7250 3025);
WIRE 16 -1 (-7250 3200)(-7250 3025);
WIRE 16 -1 (-7250 3025)(-7200 3025);
WIRE 16 -1 (-7200 3025)(-7150 3025);
WIRE 16 -1 (-7200 3025)(-7200 3200);
WIRE 16 -1 (-7150 3025)(-7150 3200);
WIRE 16 -1 (-7150 3025)(-7100 3025);
WIRE 16 -1 (-7100 3200)(-7100 3025);
WIRE 16 -1 (-7100 3025)(-7050 3025);
WIRE 16 -1 (-7050 3025)(-7050 3200);
WIRE 16 -1 (-7050 3025)(-7000 3025);
WIRE 16 -1 (-7000 3200)(-7000 3025);
WIRE 16 -1 (-7000 3025)(-6950 3025);
WIRE 16 -1 (-6950 3025)(-6950 3200);
WIRE 16 -1 (-6950 3025)(-6900 3025);
WIRE 16 -1 (-6900 3025)(-6900 3200);
WIRE 16 -1 (-6900 3025)(-6850 3025);
WIRE 16 -1 (-6850 3200)(-6850 3025);
WIRE 16 -1 (-6850 3025)(-6800 3025);
WIRE 16 -1 (-6800 3025)(-6800 3200);
WIRE 16 -1 (-6800 3025)(-6750 3025);
WIRE 16 -1 (-6750 3200)(-6750 3025);
WIRE 16 -1 (-6750 3025)(-6700 3025);
WIRE 16 -1 (-6700 3200)(-6700 3025);
WIRE 16 -1 (-6700 3025)(-6650 3025);
WIRE 16 -1 (-6650 3025)(-6650 3200);
WIRE 16 -1 (-6650 3025)(-6600 3025);
WIRE 16 -1 (-6600 3200)(-6600 3025);
WIRE 16 -1 (-6600 3025)(-6550 3025);
WIRE 16 -1 (-6550 3025)(-6550 3200);
WIRE 16 -1 (-6550 3025)(-6500 3025);
WIRE 16 -1 (-6500 3025)(-6500 3200);
WIRE 16 -1 (-6500 3025)(-6450 3025);
WIRE 16 -1 (-6450 3200)(-6450 3025);
WIRE 16 -1 (-6450 3025)(-6400 3025);
WIRE 16 -1 (-6400 3025)(-6400 3200);
WIRE 16 -1 (-6400 3025)(-6350 3025);
WIRE 16 -1 (-6350 3200)(-6350 3025);
WIRE 16 -1 (-6350 3025)(-6300 3025);
WIRE 16 -1 (-6300 3025)(-6300 3200);
WIRE 16 -1 (-6300 3025)(-6250 3025);
WIRE 16 -1 (-6250 3025)(-6250 3200);
WIRE 16 -1 (-6250 3025)(-6200 3025);
WIRE 16 -1 (-6200 3200)(-6200 3025);
WIRE 16 -1 (-6200 3025)(-6150 3025);
WIRE 16 -1 (-6150 3025)(-6100 3025);
WIRE 16 -1 (-6150 3025)(-6150 3200);
WIRE 16 -1 (-6100 3200)(-6100 3025);
WIRE 16 -1 (-6100 3025)(-6050 3025);
WIRE 16 -1 (-6050 3025)(-6050 3200);
WIRE 16 -1 (-6050 3025)(-6000 3025);
WIRE 16 -1 (-6000 3025)(-6000 3200);
WIRE 16 -1 (-6000 3025)(-5950 3025);
WIRE 16 -1 (-5950 3200)(-5950 3025);
WIRE 16 -1 (-5950 3025)(-5900 3025);
WIRE 16 -1 (-5900 3025)(-5900 3200);
WIRE 16 -1 (-5900 3025)(-5850 3025);
WIRE 16 -1 (-5850 3200)(-5850 3025);
WIRE 16 -1 (-5850 3025)(-5800 3025);
WIRE 16 -1 (-5800 3025)(-5800 3200);
WIRE 16 -1 (-5800 3025)(-5750 3025);
WIRE 16 -1 (-5750 3025)(-5750 3200);
WIRE 16 -1 (-5750 3025)(-5700 3025);
WIRE 16 -1 (-5700 3200)(-5700 3025);
WIRE 16 -1 (-5700 3025)(-5650 3025);
WIRE 16 -1 (-5650 3025)(-5650 3200);
WIRE 16 -1 (-5650 3025)(-5600 3025);
WIRE 16 -1 (-5600 3025)(-5600 3200);
WIRE 16 -1 (-5600 3025)(-5550 3025);
WIRE 16 -1 (-5550 3200)(-5550 3025);
WIRE 16 -1 (-5550 3025)(-5500 3025);
WIRE 16 -1 (-5500 3025)(-5500 3200);
WIRE 16 -1 (-5500 3025)(-5450 3025);
WIRE 16 -1 (-5450 3200)(-5450 3025);
WIRE 16 -1 (-5450 3025)(-5400 3025);
WIRE 16 -1 (-5400 3025)(-5400 3200);
WIRE 16 -1 (-5400 3025)(-5350 3025);
WIRE 16 -1 (-5350 3025)(-5350 3200);
WIRE 16 -1 (-5350 3025)(-5300 3025);
WIRE 16 -1 (-5300 3200)(-5300 3025);
WIRE 16 -1 (-5300 3025)(-5250 3025);
WIRE 16 -1 (-5250 3025)(-5250 3200);
WIRE 16 -1 (-5250 3025)(-5200 3025);
WIRE 16 -1 (-5200 3200)(-5200 3025);
WIRE 16 -1 (-5200 3025)(-5150 3025);
WIRE 16 -1 (-5150 3025)(-5100 3025);
WIRE 16 -1 (-5150 3025)(-5150 3200);
WIRE 16 -1 (-5100 3025)(-5100 3200);
WIRE 16 -1 (-5100 3025)(-5050 3025);
WIRE 16 -1 (-5050 3200)(-5050 3025);
WIRE 16 -1 (-5050 3025)(-5000 3025);
WIRE 16 -1 (-5000 3025)(-5000 3200);
WIRE 16 -1 (-5000 3025)(-4950 3025);
WIRE 16 -1 (-4950 3200)(-4950 3025);
WIRE 16 -1 (-4950 3025)(-4900 3025);
WIRE 16 -1 (-4900 3025)(-4900 3200);
WIRE 16 -1 (-4900 3025)(-4850 3025);
WIRE 16 -1 (-4850 3025)(-4850 3200);
WIRE 16 -1 (-4850 3025)(-4800 3025);
WIRE 16 -1 (-4800 3200)(-4800 3025);
WIRE 16 -1 (-4800 3025)(-4750 3025);
WIRE 16 -1 (-4750 3025)(-4750 3200);
WIRE 16 -1 (-4750 3025)(-4700 3025);
WIRE 16 -1 (-4700 3200)(-4700 3025);
WIRE 16 -1 (-4700 3025)(-4650 3025);
WIRE 16 -1 (-4650 3025)(-4650 3200);
WIRE 16 -1 (-4650 3025)(-4600 3025);
WIRE 16 -1 (-4600 3025)(-4600 3200);
WIRE 16 -1 (-4600 3025)(-4550 3025);
WIRE 16 -1 (-4550 3200)(-4550 3025);
WIRE 16 -1 (-4550 3025)(-4500 3025);
WIRE 16 -1 (-4500 3025)(-4500 3200);
WIRE 16 -1 (-4500 3025)(-4450 3025);
WIRE 16 -1 (-4450 3025)(-4450 3200);
WIRE 16 -1 (-4450 3025)(-4400 3025);
WIRE 16 -1 (-4400 3200)(-4400 3025);
WIRE 16 -1 (-4400 3025)(-4350 3025);
WIRE 16 -1 (-4350 3025)(-4350 3200);
WIRE 16 -1 (-4350 3025)(-4300 3025);
WIRE 16 -1 (-4300 3200)(-4300 3025);
WIRE 16 -1 (-4300 3025)(-4250 3025);
WIRE 16 -1 (-4250 3025)(-4250 3200);
WIRE 16 -1 (-4250 3025)(-4200 3025);
WIRE 16 -1 (-4200 3025)(-4200 3200);
WIRE 16 -1 (-4200 3025)(-4150 3025);
WIRE 16 -1 (-4150 3200)(-4150 3025);
WIRE 16 -1 (-4150 3025)(-4100 3025);
WIRE 16 -1 (-4100 3025)(-4050 3025);
WIRE 16 -1 (-4100 3025)(-4100 3200);
WIRE 16 -1 (-4050 3200)(-4050 3025);
WIRE 16 -1 (-4050 3025)(-4000 3025);
WIRE 16 -1 (-4000 3025)(-4000 3200);
WIRE 16 -1 (-4000 3025)(-3950 3025);
WIRE 16 -1 (-3950 3025)(-3950 3200);
WIRE 16 -1 (-3950 3025)(-3900 3025);
WIRE 16 -1 (-3900 3200)(-3900 3025);
WIRE 16 -1 (-3900 3025)(-3850 3025);
WIRE 16 -1 (-3850 3025)(-3850 3200);
WIRE 16 -1 (-3850 3025)(-3800 3025);
WIRE 16 -1 (-3800 3200)(-3800 3025);
WIRE 16 -1 (-3800 3025)(-3750 3025);
WIRE 16 -1 (-3750 3025)(-3750 3200);
WIRE 16 -1 (-3750 3025)(-3700 3025);
WIRE 16 -1 (-3700 3025)(-3700 3200);
WIRE 16 -1 (-3700 3025)(-3650 3025);
WIRE 16 -1 (-3650 3200)(-3650 3025);
WIRE 16 -1 (-3650 3025)(-3600 3025);
WIRE 16 -1 (-3600 3025)(-3600 3200);
WIRE 16 -1 (-3600 3025)(-3550 3025);
WIRE 16 -1 (-3550 3200)(-3550 3025);
WIRE 16 -1 (-3550 3025)(-3500 3025);
WIRE 16 -1 (-3500 3200)(-3500 3025);
WIRE 16 -1 (-3500 3025)(-3450 3025);
WIRE 16 -1 (-3450 3025)(-3450 3200);
WIRE 16 -1 (-3450 3025)(-3400 3025);
WIRE 16 -1 (-3400 3200)(-3400 3025);
WIRE 16 -1 (-3400 3025)(-3350 3025);
WIRE 16 -1 (-3350 3025)(-3350 3200);
WIRE 16 -1 (-3350 3025)(-3300 3025);
WIRE 16 -1 (-3300 3025)(-3300 3200);
WIRE 16 -1 (-3300 3025)(-3250 3025);
WIRE 16 -1 (-3250 3200)(-3250 3025);
WIRE 16 -1 (-3250 3025)(-3200 3025);
WIRE 16 -1 (-3200 3025)(-3200 3200);
WIRE 16 -1 (-3200 3025)(-3150 3025);
WIRE 16 -1 (-3150 3200)(-3150 3025);
WIRE 16 -1 (-3150 3025)(-3100 3025);
WIRE 16 -1 (-3100 3025)(-3050 3025);
WIRE 16 -1 (-3100 3025)(-3100 3200);
WIRE 16 -1 (-3050 3025)(-3050 3200);
WIRE 16 -1 (-3050 3025)(-3000 3025);
WIRE 16 -1 (-3000 3200)(-3000 3025);
WIRE 16 -1 (-3000 3025)(-2950 3025);
WIRE 16 -1 (-2950 3025)(-2950 3200);
WIRE 16 -1 (-2950 3025)(-2900 3025);
WIRE 16 -1 (-2900 3200)(-2900 3025);
WIRE 16 -1 (-2900 3025)(-2850 3025);
WIRE 16 -1 (-2850 3025)(-2850 3200);
WIRE 16 -1 (-2850 3025)(-2800 3025);
WIRE 16 -1 (-2800 3025)(-2800 3200);
WIRE 16 -1 (-2800 3025)(-2750 3025);
WIRE 16 -1 (-2750 3200)(-2750 3025);
WIRE 16 -1 (-2750 3025)(-2700 3025);
WIRE 16 -1 (-2700 3025)(-2700 3200);
WIRE 16 -1 (-2700 3025)(-2650 3025);
WIRE 16 -1 (-2650 3200)(-2650 3025);
WIRE 16 -1 (-2650 3025)(-2600 3025);
WIRE 16 -1 (-2600 3025)(-2600 3200);
WIRE 16 -1 (-2600 3025)(-2550 3025);
WIRE 16 -1 (-2550 3025)(-2550 3200);
WIRE 16 -1 (-2550 3025)(-2500 3025);
WIRE 16 -1 (-2500 3200)(-2500 3025);
WIRE 16 -1 (-2500 3025)(-2450 3025);
WIRE 16 -1 (-2450 3025)(-2450 3200);
WIRE 16 -1 (-2450 3025)(-2400 3025);
WIRE 16 -1 (-2400 3025)(-2400 3200);
WIRE 16 -1 (-2400 3025)(-2350 3025);
WIRE 16 -1 (-2350 3200)(-2350 3025);
WIRE 16 -1 (-2350 3025)(-2300 3025);
WIRE 16 -1 (-2300 3200)(-2300 3025);
WIRE 16 -1 (-2300 3025)(-2250 3025);
WIRE 16 -1 (-2250 3200)(-2250 3025);
WIRE 16 -1 (-2250 3025)(-2200 3025);
WIRE 16 -1 (-2200 3200)(-2200 3025);
WIRE 16 -1 (-2200 3025)(-2150 3025);
WIRE 16 -1 (-2150 3200)(-2150 3025);
WIRE 16 -1 (-2100 3025)(-2150 3025);
WIRE 16 -1 (-1925 3025)(-2100 3025);
WIRE 16 -1 (-2100 3200)(-2100 3025);
WIRE 16 -1 (-8000 4300)(-8000 4475);
WIRE 16 -1 (-8000 4475)(-7950 4475);
WIRE 16 -1 (-7950 4300)(-7950 4475);
WIRE 16 -1 (-7950 4475)(-7900 4475);
WIRE 16 -1 (-7900 4475)(-7850 4475);
WIRE 16 -1 (-7900 4300)(-7900 4475);
WIRE 16 -1 (-7850 4300)(-7850 4475);
WIRE 16 -1 (-7850 4475)(-7800 4475);
WIRE 16 -1 (-7800 4300)(-7800 4475);
WIRE 16 -1 (-7800 4475)(-7750 4475);
WIRE 16 -1 (-7750 4300)(-7750 4475);
WIRE 16 -1 (-7750 4475)(-7700 4475);
WIRE 16 -1 (-7700 4300)(-7700 4475);
WIRE 16 -1 (-7700 4475)(-7650 4475);
WIRE 16 -1 (-7650 4475)(-7600 4475);
WIRE 16 -1 (-7650 4300)(-7650 4475);
WIRE 16 -1 (-7600 4300)(-7600 4475);
WIRE 16 -1 (-7600 4475)(-7550 4475);
WIRE 16 -1 (-7550 4300)(-7550 4475);
WIRE 16 -1 (-7550 4475)(-7500 4475);
WIRE 16 -1 (-7500 4300)(-7500 4475);
WIRE 16 -1 (-7500 4475)(-7450 4475);
WIRE 16 -1 (-7450 4300)(-7450 4475);
WIRE 16 -1 (-7450 4475)(-7400 4475);
WIRE 16 -1 (-7400 4475)(-7350 4475);
WIRE 16 -1 (-7400 4300)(-7400 4475);
WIRE 16 -1 (-7350 4300)(-7350 4475);
WIRE 16 -1 (-7350 4475)(-7300 4475);
WIRE 16 -1 (-7300 4300)(-7300 4475);
WIRE 16 -1 (-7300 4475)(-7250 4475);
WIRE 16 -1 (-7250 4300)(-7250 4475);
WIRE 16 -1 (-7250 4475)(-7200 4475);
WIRE 16 -1 (-7200 4300)(-7200 4475);
WIRE 16 -1 (-7200 4475)(-7150 4475);
WIRE 16 -1 (-7150 4475)(-7100 4475);
WIRE 16 -1 (-7150 4300)(-7150 4475);
WIRE 16 -1 (-7100 4300)(-7100 4475);
WIRE 16 -1 (-7100 4475)(-7050 4475);
WIRE 16 -1 (-7050 4300)(-7050 4475);
WIRE 16 -1 (-7050 4475)(-7000 4475);
WIRE 16 -1 (-7000 4300)(-7000 4475);
WIRE 16 -1 (-7000 4475)(-6950 4475);
WIRE 16 -1 (-6950 4300)(-6950 4475);
WIRE 16 -1 (-6950 4475)(-6900 4475);
WIRE 16 -1 (-6900 4475)(-6850 4475);
WIRE 16 -1 (-6900 4300)(-6900 4475);
WIRE 16 -1 (-6850 4300)(-6850 4475);
WIRE 16 -1 (-6850 4475)(-6800 4475);
WIRE 16 -1 (-6800 4300)(-6800 4475);
WIRE 16 -1 (-6800 4475)(-6750 4475);
WIRE 16 -1 (-6750 4300)(-6750 4475);
WIRE 16 -1 (-6750 4475)(-6700 4475);
WIRE 16 -1 (-6700 4300)(-6700 4475);
WIRE 16 -1 (-6700 4475)(-6650 4475);
WIRE 16 -1 (-6650 4475)(-6600 4475);
WIRE 16 -1 (-6650 4300)(-6650 4475);
WIRE 16 -1 (-6600 4300)(-6600 4475);
WIRE 16 -1 (-6600 4475)(-6550 4475);
WIRE 16 -1 (-6550 4300)(-6550 4475);
WIRE 16 -1 (-6550 4475)(-6500 4475);
WIRE 16 -1 (-6500 4300)(-6500 4475);
WIRE 16 -1 (-6500 4475)(-6450 4475);
WIRE 16 -1 (-6450 4300)(-6450 4475);
WIRE 16 -1 (-6450 4475)(-6400 4475);
WIRE 16 -1 (-6400 4300)(-6400 4475);
WIRE 16 -1 (-6400 4475)(-6350 4475);
WIRE 16 -1 (-6350 4475)(-6300 4475);
WIRE 16 -1 (-6350 4300)(-6350 4475);
WIRE 16 -1 (-6300 4300)(-6300 4475);
WIRE 16 -1 (-6300 4475)(-6250 4475);
WIRE 16 -1 (-6250 4300)(-6250 4475);
WIRE 16 -1 (-6250 4475)(-6200 4475);
WIRE 16 -1 (-6200 4300)(-6200 4475);
WIRE 16 -1 (-6200 4475)(-6150 4475);
WIRE 16 -1 (-6150 4300)(-6150 4475);
WIRE 16 -1 (-6150 4475)(-6100 4475);
WIRE 16 -1 (-6100 4475)(-6050 4475);
WIRE 16 -1 (-6100 4300)(-6100 4475);
WIRE 16 -1 (-6050 4300)(-6050 4475);
WIRE 16 -1 (-6050 4475)(-6000 4475);
WIRE 16 -1 (-6000 4300)(-6000 4475);
WIRE 16 -1 (-6000 4475)(-5950 4475);
WIRE 16 -1 (-5950 4300)(-5950 4475);
WIRE 16 -1 (-5950 4475)(-5900 4475);
WIRE 16 -1 (-5900 4300)(-5900 4475);
WIRE 16 -1 (-5900 4475)(-5850 4475);
WIRE 16 -1 (-5850 4475)(-5800 4475);
WIRE 16 -1 (-5850 4300)(-5850 4475);
WIRE 16 -1 (-5800 4300)(-5800 4475);
WIRE 16 -1 (-5800 4475)(-5750 4475);
WIRE 16 -1 (-5750 4300)(-5750 4475);
WIRE 16 -1 (-5750 4475)(-5700 4475);
WIRE 16 -1 (-5700 4300)(-5700 4475);
WIRE 16 -1 (-5700 4475)(-5650 4475);
WIRE 16 -1 (-5650 4300)(-5650 4475);
WIRE 16 -1 (-5650 4475)(-5600 4475);
WIRE 16 -1 (-5600 4475)(-5550 4475);
WIRE 16 -1 (-5600 4300)(-5600 4475);
WIRE 16 -1 (-5550 4300)(-5550 4475);
WIRE 16 -1 (-5550 4475)(-5500 4475);
WIRE 16 -1 (-5500 4300)(-5500 4475);
WIRE 16 -1 (-5500 4475)(-5450 4475);
WIRE 16 -1 (-5450 4300)(-5450 4475);
WIRE 16 -1 (-5450 4475)(-5400 4475);
WIRE 16 -1 (-5400 4300)(-5400 4475);
WIRE 16 -1 (-5400 4475)(-5350 4475);
WIRE 16 -1 (-5350 4475)(-5300 4475);
WIRE 16 -1 (-5350 4300)(-5350 4475);
WIRE 16 -1 (-5300 4300)(-5300 4475);
WIRE 16 -1 (-5300 4475)(-5250 4475);
WIRE 16 -1 (-5250 4300)(-5250 4475);
WIRE 16 -1 (-5250 4475)(-5200 4475);
WIRE 16 -1 (-5200 4300)(-5200 4475);
WIRE 16 -1 (-5200 4475)(-5150 4475);
WIRE 16 -1 (-5150 4300)(-5150 4475);
WIRE 16 -1 (-5150 4475)(-5100 4475);
WIRE 16 -1 (-5100 4475)(-5050 4475);
WIRE 16 -1 (-5100 4300)(-5100 4475);
WIRE 16 -1 (-5050 4300)(-5050 4475);
WIRE 16 -1 (-5050 4475)(-5000 4475);
WIRE 16 -1 (-5000 4300)(-5000 4475);
WIRE 16 -1 (-5000 4475)(-4950 4475);
WIRE 16 -1 (-4950 4300)(-4950 4475);
WIRE 16 -1 (-4950 4475)(-4900 4475);
WIRE 16 -1 (-4900 4300)(-4900 4475);
WIRE 16 -1 (-4900 4475)(-4850 4475);
WIRE 16 -1 (-4850 4475)(-4800 4475);
WIRE 16 -1 (-4850 4300)(-4850 4475);
WIRE 16 -1 (-4800 4300)(-4800 4475);
WIRE 16 -1 (-4800 4475)(-4750 4475);
WIRE 16 -1 (-4750 4300)(-4750 4475);
WIRE 16 -1 (-4750 4475)(-4700 4475);
WIRE 16 -1 (-4700 4300)(-4700 4475);
WIRE 16 -1 (-4700 4475)(-4650 4475);
WIRE 16 -1 (-4650 4300)(-4650 4475);
WIRE 16 -1 (-4650 4475)(-4600 4475);
WIRE 16 -1 (-4600 4475)(-4550 4475);
WIRE 16 -1 (-4600 4300)(-4600 4475);
WIRE 16 -1 (-4550 4300)(-4550 4475);
WIRE 16 -1 (-4550 4475)(-4500 4475);
WIRE 16 -1 (-4500 4300)(-4500 4475);
WIRE 16 -1 (-4500 4475)(-4450 4475);
WIRE 16 -1 (-4450 4300)(-4450 4475);
WIRE 16 -1 (-4450 4475)(-4400 4475);
WIRE 16 -1 (-4400 4300)(-4400 4475);
WIRE 16 -1 (-4400 4475)(-4350 4475);
WIRE 16 -1 (-4350 4475)(-4300 4475);
WIRE 16 -1 (-4350 4300)(-4350 4475);
WIRE 16 -1 (-4300 4300)(-4300 4475);
WIRE 16 -1 (-4300 4475)(-4250 4475);
WIRE 16 -1 (-4250 4300)(-4250 4475);
WIRE 16 -1 (-4250 4475)(-4200 4475);
WIRE 16 -1 (-4200 4300)(-4200 4475);
WIRE 16 -1 (-4200 4475)(-4150 4475);
WIRE 16 -1 (-4150 4300)(-4150 4475);
WIRE 16 -1 (-4150 4475)(-4100 4475);
WIRE 16 -1 (-4100 4300)(-4100 4475);
WIRE 16 -1 (-4100 4475)(-4050 4475);
WIRE 16 -1 (-4050 4475)(-4000 4475);
WIRE 16 -1 (-4050 4300)(-4050 4475);
WIRE 16 -1 (-4000 4300)(-4000 4475);
WIRE 16 -1 (-4000 4475)(-3950 4475);
WIRE 16 -1 (-3950 4300)(-3950 4475);
WIRE 16 -1 (-3950 4475)(-3900 4475);
WIRE 16 -1 (-3900 4300)(-3900 4475);
WIRE 16 -1 (-3900 4475)(-3850 4475);
WIRE 16 -1 (-3850 4300)(-3850 4475);
WIRE 16 -1 (-3850 4475)(-3800 4475);
WIRE 16 -1 (-3800 4475)(-3750 4475);
WIRE 16 -1 (-3800 4300)(-3800 4475);
WIRE 16 -1 (-3750 4300)(-3750 4475);
WIRE 16 -1 (-3750 4475)(-3700 4475);
WIRE 16 -1 (-3700 4300)(-3700 4475);
WIRE 16 -1 (-3700 4475)(-3650 4475);
WIRE 16 -1 (-3650 4300)(-3650 4475);
WIRE 16 -1 (-3650 4475)(-3600 4475);
WIRE 16 -1 (-3600 4300)(-3600 4475);
WIRE 16 -1 (-3600 4475)(-3550 4475);
WIRE 16 -1 (-3550 4475)(-3500 4475);
WIRE 16 -1 (-3550 4300)(-3550 4475);
WIRE 16 -1 (-3500 4300)(-3500 4475);
WIRE 16 -1 (-3500 4475)(-3450 4475);
WIRE 16 -1 (-3450 4300)(-3450 4475);
WIRE 16 -1 (-3450 4475)(-3400 4475);
WIRE 16 -1 (-3400 4300)(-3400 4475);
WIRE 16 -1 (-3400 4475)(-3350 4475);
WIRE 16 -1 (-3350 4300)(-3350 4475);
WIRE 16 -1 (-3350 4475)(-3300 4475);
WIRE 16 -1 (-3300 4475)(-3250 4475);
WIRE 16 -1 (-3300 4300)(-3300 4475);
WIRE 16 -1 (-3250 4300)(-3250 4475);
WIRE 16 -1 (-3250 4475)(-3200 4475);
WIRE 16 -1 (-3200 4300)(-3200 4475);
WIRE 16 -1 (-3200 4475)(-3150 4475);
WIRE 16 -1 (-3150 4300)(-3150 4475);
WIRE 16 -1 (-3150 4475)(-3100 4475);
WIRE 16 -1 (-3100 4300)(-3100 4475);
WIRE 16 -1 (-3100 4475)(-3050 4475);
WIRE 16 -1 (-3050 4475)(-3000 4475);
WIRE 16 -1 (-3050 4300)(-3050 4475);
WIRE 16 -1 (-3000 4300)(-3000 4475);
WIRE 16 -1 (-3000 4475)(-2950 4475);
WIRE 16 -1 (-2950 4300)(-2950 4475);
WIRE 16 -1 (-2950 4475)(-2900 4475);
WIRE 16 -1 (-2900 4300)(-2900 4475);
WIRE 16 -1 (-2900 4475)(-2850 4475);
WIRE 16 -1 (-2850 4300)(-2850 4475);
WIRE 16 -1 (-2850 4475)(-2800 4475);
WIRE 16 -1 (-2800 4475)(-2750 4475);
WIRE 16 -1 (-2800 4300)(-2800 4475);
WIRE 16 -1 (-2750 4300)(-2750 4475);
WIRE 16 -1 (-2750 4475)(-2700 4475);
WIRE 16 -1 (-2700 4300)(-2700 4475);
WIRE 16 -1 (-2700 4475)(-2650 4475);
WIRE 16 -1 (-2650 4300)(-2650 4475);
WIRE 16 -1 (-2650 4475)(-2600 4475);
WIRE 16 -1 (-2600 4300)(-2600 4475);
WIRE 16 -1 (-2600 4475)(-2550 4475);
WIRE 16 -1 (-2550 4475)(-2500 4475);
WIRE 16 -1 (-2550 4300)(-2550 4475);
WIRE 16 -1 (-2500 4300)(-2500 4475);
WIRE 16 -1 (-2500 4475)(-2450 4475);
WIRE 16 -1 (-2450 4300)(-2450 4475);
WIRE 16 -1 (-2450 4475)(-2400 4475);
WIRE 16 -1 (-2400 4300)(-2400 4475);
WIRE 16 -1 (-2400 4475)(-2350 4475);
WIRE 16 -1 (-2350 4300)(-2350 4475);
WIRE 16 -1 (-2350 4475)(-2300 4475);
WIRE 16 -1 (-2300 4475)(-2250 4475);
WIRE 16 -1 (-2300 4300)(-2300 4475);
WIRE 16 -1 (-2250 4300)(-2250 4475);
WIRE 16 -1 (-2250 4475)(-2200 4475);
WIRE 16 -1 (-2200 4300)(-2200 4475);
WIRE 16 -1 (-2200 4475)(-2150 4475);
WIRE 16 -1 (-2150 4300)(-2150 4475);
WIRE 16 -1 (-2100 4475)(-2150 4475);
WIRE 16 -1 (-2100 4300)(-2100 4475);
WIRE 16 -1 (-2050 4475)(-2100 4475);
WIRE 16 -1 (-2050 4300)(-2050 4475);
WIRE 16 -1 (-2000 4475)(-2050 4475);
WIRE 16 -1 (-1950 4475)(-2000 4475);
WIRE 16 -1 (-2000 4300)(-2000 4475);
WIRE 16 -1 (-1950 4300)(-1950 4475);
WIRE 16 -1 (-1900 4475)(-1950 4475);
WIRE 16 -1 (-1900 4300)(-1900 4475);
WIRE 16 -1 (-1850 4475)(-1900 4475);
WIRE 16 -1 (-1850 4300)(-1850 4475);
WIRE 16 -1 (-1800 4475)(-1850 4475);
WIRE 16 -1 (-1800 4300)(-1800 4475);
WIRE 16 -1 (-1750 4475)(-1800 4475);
WIRE 16 -1 (-1700 4475)(-1750 4475);
WIRE 16 -1 (-1750 4475)(-1750 4300);
WIRE 16 -1 (-1650 4475)(-1700 4475);
WIRE 16 -1 (-1700 4475)(-1700 4300);
WIRE 16 -1 (-1600 4475)(-1650 4475);
WIRE 16 -1 (-1650 4475)(-1650 4300);
WIRE 16 -1 (-1350 4475)(-1600 4475);
WIRE 16 -1 (-1600 4475)(-1600 4300);
DOT 1 (-7950 3025);
DOT 1 (-1600 4475);
DOT 1 (-1650 4475);
DOT 1 (-1700 4475);
DOT 1 (-1750 4475);
DOT 1 (-1900 4475);
DOT 1 (-1800 4475);
DOT 1 (-1850 4475);
DOT 1 (-1950 4475);
DOT 1 (-2000 4475);
DOT 1 (-2150 4475);
DOT 1 (-2100 4475);
DOT 1 (-2050 4475);
DOT 1 (-2250 4475);
DOT 1 (-2200 4475);
DOT 1 (-2300 4475);
DOT 1 (-2350 4475);
DOT 1 (-2400 4475);
DOT 1 (-2500 4475);
DOT 1 (-2450 4475);
DOT 1 (-2550 4475);
DOT 1 (-2600 4475);
DOT 1 (-2650 4475);
DOT 1 (-2800 4475);
DOT 1 (-2750 4475);
DOT 1 (-2700 4475);
DOT 1 (-2850 4475);
DOT 1 (-2900 4475);
DOT 1 (-3050 4475);
DOT 1 (-3000 4475);
DOT 1 (-2950 4475);
DOT 1 (-3100 4475);
DOT 1 (-3150 4475);
DOT 1 (-3200 4475);
DOT 1 (-3250 4475);
DOT 1 (-3300 4475);
DOT 1 (-3400 4475);
DOT 1 (-3350 4475);
DOT 1 (-3450 4475);
DOT 1 (-3550 4475);
DOT 1 (-3500 4475);
DOT 1 (-3650 4475);
DOT 1 (-3600 4475);
DOT 1 (-3700 4475);
DOT 1 (-3750 4475);
DOT 1 (-3800 4475);
DOT 1 (-3950 4475);
DOT 1 (-3850 4475);
DOT 1 (-3900 4475);
DOT 1 (-4000 4475);
DOT 1 (-4050 4475);
DOT 1 (-2100 3025);
DOT 1 (-2150 3025);
DOT 1 (-2200 3025);
DOT 1 (-2250 3025);
DOT 1 (-2300 3025);
DOT 1 (-2350 3025);
DOT 1 (-2400 3025);
DOT 1 (-2450 3025);
DOT 1 (-2500 3025);
DOT 1 (-2550 3025);
DOT 1 (-2600 3025);
DOT 1 (-2650 3025);
DOT 1 (-2700 3025);
DOT 1 (-2750 3025);
DOT 1 (-2800 3025);
DOT 1 (-2850 3025);
DOT 1 (-2900 3025);
DOT 1 (-2950 3025);
DOT 1 (-3000 3025);
DOT 1 (-3050 3025);
DOT 1 (-3100 3025);
DOT 1 (-3150 3025);
DOT 1 (-3200 3025);
DOT 1 (-3250 3025);
DOT 1 (-3300 3025);
DOT 1 (-3350 3025);
DOT 1 (-3400 3025);
DOT 1 (-3450 3025);
DOT 1 (-3550 3025);
DOT 1 (-3500 3025);
DOT 1 (-3600 3025);
DOT 1 (-3650 3025);
DOT 1 (-3700 3025);
DOT 1 (-3750 3025);
DOT 1 (-3800 3025);
DOT 1 (-3850 3025);
DOT 1 (-3900 3025);
DOT 1 (-3950 3025);
DOT 1 (-4000 3025);
DOT 1 (-4050 3025);
DOT 1 (-4200 4475);
DOT 1 (-4150 4475);
DOT 1 (-4100 4475);
DOT 1 (-4300 4475);
DOT 1 (-4250 4475);
DOT 1 (-4350 4475);
DOT 1 (-4400 4475);
DOT 1 (-4450 4475);
DOT 1 (-4550 4475);
DOT 1 (-4500 4475);
DOT 1 (-4600 4475);
DOT 1 (-4650 4475);
DOT 1 (-4700 4475);
DOT 1 (-4800 4475);
DOT 1 (-4850 4475);
DOT 1 (-4750 4475);
DOT 1 (-4900 4475);
DOT 1 (-4950 4475);
DOT 1 (-5100 4475);
DOT 1 (-5050 4475);
DOT 1 (-5000 4475);
DOT 1 (-5150 4475);
DOT 1 (-5200 4475);
DOT 1 (-5350 4475);
DOT 1 (-5300 4475);
DOT 1 (-5250 4475);
DOT 1 (-5450 4475);
DOT 1 (-5400 4475);
DOT 1 (-5500 4475);
DOT 1 (-5550 4475);
DOT 1 (-5600 4475);
DOT 1 (-5700 4475);
DOT 1 (-5750 4475);
DOT 1 (-5800 4475);
DOT 1 (-5850 4475);
DOT 1 (-6000 4475);
DOT 1 (-5900 4475);
DOT 1 (-5950 4475);
DOT 1 (-6050 4475);
DOT 1 (-6100 4475);
DOT 1 (-6250 4475);
DOT 1 (-6150 4475);
DOT 1 (-6300 4475);
DOT 1 (-6350 4475);
DOT 1 (-6400 4475);
DOT 1 (-6450 4475);
DOT 1 (-6500 4475);
DOT 1 (-6600 4475);
DOT 1 (-6550 4475);
DOT 1 (-6700 4475);
DOT 1 (-6750 4475);
DOT 1 (-6800 4475);
DOT 1 (-6900 4475);
DOT 1 (-6950 4475);
DOT 1 (-7000 4475);
DOT 1 (-7150 4475);
DOT 1 (-7100 4475);
DOT 1 (-7050 4475);
DOT 1 (-7200 4475);
DOT 1 (-7250 4475);
DOT 1 (-7400 4475);
DOT 1 (-7350 4475);
DOT 1 (-7300 4475);
DOT 1 (-7500 4475);
DOT 1 (-7450 4475);
DOT 1 (-7550 4475);
DOT 1 (-7650 4475);
DOT 1 (-7750 4475);
DOT 1 (-7700 4475);
DOT 1 (-7800 4475);
DOT 1 (-7850 4475);
DOT 1 (-7900 4475);
DOT 1 (-7950 4475);
DOT 1 (-4100 3025);
DOT 1 (-4150 3025);
DOT 1 (-4200 3025);
DOT 1 (-4250 3025);
DOT 1 (-4300 3025);
DOT 1 (-4350 3025);
DOT 1 (-4400 3025);
DOT 1 (-4450 3025);
DOT 1 (-4500 3025);
DOT 1 (-4550 3025);
DOT 1 (-4600 3025);
DOT 1 (-4650 3025);
DOT 1 (-4700 3025);
DOT 1 (-4750 3025);
DOT 1 (-4800 3025);
DOT 1 (-4850 3025);
DOT 1 (-4900 3025);
DOT 1 (-4950 3025);
DOT 1 (-5000 3025);
DOT 1 (-5050 3025);
DOT 1 (-5100 3025);
DOT 1 (-5150 3025);
DOT 1 (-5200 3025);
DOT 1 (-5250 3025);
DOT 1 (-5300 3025);
DOT 1 (-5350 3025);
DOT 1 (-5400 3025);
DOT 1 (-5450 3025);
DOT 1 (-5500 3025);
DOT 1 (-5550 3025);
DOT 1 (-5600 3025);
DOT 1 (-5650 3025);
DOT 1 (-5700 3025);
DOT 1 (-5750 3025);
DOT 1 (-5800 3025);
DOT 1 (-5850 3025);
DOT 1 (-5900 3025);
DOT 1 (-5950 3025);
DOT 1 (-6000 3025);
DOT 1 (-6050 3025);
DOT 1 (-6100 3025);
DOT 1 (-6150 3025);
DOT 1 (-6200 3025);
DOT 1 (-6250 3025);
DOT 1 (-6300 3025);
DOT 1 (-6350 3025);
DOT 1 (-6400 3025);
DOT 1 (-6550 3025);
DOT 1 (-6600 3025);
DOT 1 (-6650 3025);
DOT 1 (-6700 3025);
DOT 1 (-6750 3025);
DOT 1 (-6800 3025);
DOT 1 (-6850 3025);
DOT 1 (-6900 3025);
DOT 1 (-6950 3025);
DOT 1 (-7000 3025);
DOT 1 (-7050 3025);
DOT 1 (-7100 3025);
DOT 1 (-7150 3025);
DOT 1 (-7200 3025);
DOT 1 (-7250 3025);
DOT 1 (-7300 3025);
DOT 1 (-7350 3025);
DOT 1 (-7400 3025);
DOT 1 (-7450 3025);
DOT 1 (-7500 3025);
DOT 1 (-7650 3025);
DOT 1 (-7700 3025);
DOT 1 (-7750 3025);
DOT 1 (-7800 3025);
DOT 1 (-7850 3025);
DOT 1 (-7900 3025);
DOT 1 (-7600 4475);
DOT 1 (-5650 4475);
DOT 1 (-6200 4475);
DOT 1 (-6850 4475);
DOT 1 (-6450 3025);
DOT 1 (-6500 3025);
DOT 1 (-7550 3025);
DOT 1 (-7600 3025);
DOT 1 (-6650 4475);
QUIT
